(kicad_pcb
	(version 20260206)
	(generator "pcbnew")
	(generator_version "10.0")
	(general
		(thickness 1.6)
		(legacy_teardrops no)
	)
	(paper "A4")
	(title_block
		(title "v1-chassis-manager — T6M_CM_d_v01_1031_1645.brd")
		(comment 1 "Open CloudServer (Microsoft) / footprints 181-183 of 2512")
	)
	(layers
		(0 "F.Cu" signal "TOP")
		(4 "In1.Cu" signal "GND1")
		(6 "In2.Cu" signal "IN1")
		(8 "In3.Cu" signal "VCC1")
		(10 "In4.Cu" signal "VCC2")
		(12 "In5.Cu" signal "GND2")
		(14 "In6.Cu" signal "IN2")
		(16 "In7.Cu" signal "IN3")
		(18 "In8.Cu" signal "GND3")
		(2 "B.Cu" signal "BOTTOM")
		(9 "F.Adhes" user "F.Adhesive")
		(11 "B.Adhes" user "B.Adhesive")
		(13 "F.Paste" user "Package Geometry/Pastemask Top")
		(15 "B.Paste" user "Package Geometry/Pastemask Bottom")
		(5 "F.SilkS" user "Ref Des/Silkscreen Top")
		(7 "B.SilkS" user "Ref Des/Silkscreen Bottom")
		(1 "F.Mask" user "Board Geometry/Soldermask Top")
		(3 "B.Mask" user "Board Geometry/Soldermask Bottom")
		(17 "Dwgs.User" user "User.Drawings")
		(19 "Cmts.User" user "User.Comments")
		(21 "Eco1.User" user "User.Eco1")
		(23 "Eco2.User" user "User.Eco2")
		(25 "Edge.Cuts" user "Board Geometry/Outline")
		(27 "Margin" user)
		(31 "F.CrtYd" user "Package Geometry/Place Bound Top")
		(29 "B.CrtYd" user "Package Geometry/Place Bound Bottom")
		(35 "F.Fab" user "Ref Des/Assembly Top")
		(33 "B.Fab" user "Ref Des/Assembly Bottom")
	)
	(footprint ""
		(layer "F.Cu")
		(at 150.293578 -57.249822 -90)
		(property "Reference" "R517"
			(at -14.50213 -26.0858 90)
			(unlocked yes)
			(layer "F.SilkS")
			(effects
				(font
					(size 0.7874 0.5842)
					(thickness 0.1524)
				)
				(justify left)
			)
		)
		(property "Value" ""
			(at 0 0 270)
			(layer "F.Fab")
			(effects
				(font
					(size 1.27 1.27)
				)
			)
		)
		(duplicate_pad_numbers_are_jumpers no)
		(fp_line
			(start -0.7874 0.4064)
			(end -0.7874 -0.4064)
			(stroke
				(width 0.1524)
				(type default)
			)
			(layer "F.SilkS")
		)
		(fp_line
			(start 0.7874 0.4064)
			(end -0.7874 0.4064)
			(stroke
				(width 0.1524)
				(type default)
			)
			(layer "F.SilkS")
		)
		(fp_line
			(start -0.7874 -0.4064)
			(end 0.7874 -0.4064)
			(stroke
				(width 0.1524)
				(type default)
			)
			(layer "F.SilkS")
		)
		(fp_line
			(start 0.7874 -0.4064)
			(end 0.7874 0.4064)
			(stroke
				(width 0.1524)
				(type default)
			)
			(layer "F.SilkS")
		)
		(fp_poly
			(pts
				(xy -0.508 0.2794) (xy -0.508 0.2286) (xy -0.635 0.2286) (xy -0.635 -0.254) (xy -0.5334 -0.254)
				(xy -0.5334 -0.2794) (xy 0.5334 -0.2794) (xy 0.5334 -0.254) (xy 0.635 -0.254) (xy 0.635 0.254) (xy 0.5334 0.254)
				(xy 0.5334 0.2794)
			)
			(stroke
				(width 0)
				(type default)
			)
			(fill no)
			(layer "F.CrtYd")
		)
		(pad "1" smd rect
			(at 0.40005 0 270)
			(size 0.4572 0.508)
			(layers "F.Cu" "F.Mask" "F.Paste")
			(net "P3V3_NODE1")
		)
		(pad "2" smd rect
			(at -0.40005 0 270)
			(size 0.4572 0.508)
			(layers "F.Cu" "F.Mask" "F.Paste")
			(net "SATA_NODE1_GPIO5")
		)
	)
	(footprint ""
		(layer "F.Cu")
		(at 165.811454 -167.764968 180)
		(property "Reference" "C434"
			(at -1.295908 -0.439928 0)
			(unlocked yes)
			(layer "F.SilkS")
			(effects
				(font
					(size 0.7874 0.5842)
					(thickness 0.1524)
				)
				(justify left)
			)
		)
		(property "Value" ""
			(at 0 0 180)
			(layer "F.Fab")
			(effects
				(font
					(size 1.27 1.27)
				)
			)
		)
		(duplicate_pad_numbers_are_jumpers no)
		(fp_line
			(start 0.7874 0.4064)
			(end -0.7874 0.4064)
			(stroke
				(width 0.1524)
				(type default)
			)
			(layer "F.SilkS")
		)
		(fp_line
			(start 0.7874 -0.4064)
			(end 0.7874 0.4064)
			(stroke
				(width 0.1524)
				(type default)
			)
			(layer "F.SilkS")
		)
		(fp_line
			(start 0 0.381)
			(end 0 -0.381)
			(stroke
				(width 0.1524)
				(type default)
			)
			(layer "F.SilkS")
		)
		(fp_line
			(start -0.7874 0.4064)
			(end -0.7874 -0.4064)
			(stroke
				(width 0.1524)
				(type default)
			)
			(layer "F.SilkS")
		)
		(fp_line
			(start -0.7874 -0.4064)
			(end 0.7874 -0.4064)
			(stroke
				(width 0.1524)
				(type default)
			)
			(layer "F.SilkS")
		)
		(fp_poly
			(pts
				(xy -0.5334 0.254) (xy -0.635 0.254) (xy -0.635 0.2286) (xy -0.635 -0.254) (xy -0.5334 -0.254) (xy -0.5334 -0.2794)
				(xy 0.5334 -0.2794) (xy 0.5334 -0.254) (xy 0.635 -0.254) (xy 0.635 0.254) (xy 0.5334 0.254) (xy 0.5334 0.2794)
				(xy -0.508 0.2794) (xy -0.5334 0.2794)
			)
			(stroke
				(width 0)
				(type default)
			)
			(fill no)
			(layer "F.CrtYd")
		)
		(pad "1" smd rect
			(at 0.40005 0 180)
			(size 0.4572 0.508)
			(layers "F.Cu" "F.Mask" "F.Paste")
			(net "P3V3_NODE1")
		)
		(pad "2" smd rect
			(at -0.40005 0 180)
			(size 0.4572 0.508)
			(layers "F.Cu" "F.Mask" "F.Paste")
			(net "GND")
		)
	)
	(footprint ""
		(layer "F.Cu")
		(at 56.24576 -188.126624 90)
		(property "Reference" "C715"
			(at 4.548886 0.310642 90)
			(unlocked yes)
			(layer "F.SilkS")
			(effects
				(font
					(size 0.7874 0.5842)
					(thickness 0.1524)
				)
				(justify left)
			)
		)
		(property "Value" ""
			(at 0 0 90)
			(layer "F.Fab")
			(effects
				(font
					(size 1.27 1.27)
				)
			)
		)
		(duplicate_pad_numbers_are_jumpers no)
		(fp_line
			(start 0.7874 -0.4064)
			(end 0.7874 0.4064)
			(stroke
				(width 0.1524)
				(type default)
			)
			(layer "F.SilkS")
		)
		(fp_line
			(start -0.7874 -0.4064)
			(end 0.7874 -0.4064)
			(stroke
				(width 0.1524)
				(type default)
			)
			(layer "F.SilkS")
		)
		(fp_line
			(start 0 0.381)
			(end 0 -0.381)
			(stroke
				(width 0.1524)
				(type default)
			)
			(layer "F.SilkS")
		)
		(fp_line
			(start 0.7874 0.4064)
			(end -0.7874 0.4064)
			(stroke
				(width 0.1524)
				(type default)
			)
			(layer "F.SilkS")
		)
		(fp_line
			(start -0.7874 0.4064)
			(end -0.7874 -0.4064)
			(stroke
				(width 0.1524)
				(type default)
			)
			(layer "F.SilkS")
		)
		(fp_poly
			(pts
				(xy -0.5334 0.254) (xy -0.635 0.254) (xy -0.635 0.2286) (xy -0.635 -0.254) (xy -0.5334 -0.254) (xy -0.5334 -0.2794)
				(xy 0.5334 -0.2794) (xy 0.5334 -0.254) (xy 0.635 -0.254) (xy 0.635 0.254) (xy 0.5334 0.254) (xy 0.5334 0.2794)
				(xy -0.508 0.2794) (xy -0.5334 0.2794)
			)
			(stroke
				(width 0)
				(type default)
			)
			(fill no)
			(layer "F.CrtYd")
		)
		(pad "1" smd rect
			(at 0.40005 0 90)
			(size 0.4572 0.508)
			(layers "F.Cu" "F.Mask" "F.Paste")
			(net "UART_T2_NODE4_TXD_R")
		)
		(pad "2" smd rect
			(at -0.40005 0 90)
			(size 0.4572 0.508)
			(layers "F.Cu" "F.Mask" "F.Paste")
			(net "GND")
		)
	)
)
